(kicad_sch (version 20211123) (generator eeschema)

  (paper "A3")

  (title_block
    (title "SA800U (Snapdragon 845) Baseboard")
    (date "2023-10-19")
    (rev "1.0.3")
    (company "Antmicro Ltd.")
    (comment 1 "www.antmicro.com")
  )

  (junction (at 314.325 116.84) (diameter 0) (color 0 0 0 0)
  )
  (junction (at 100.965 130.175) (diameter 0) (color 0 0 0 0)
  )
  (junction (at 100.965 142.875) (diameter 0) (color 0 0 0 0)
  )
  (junction (at 314.325 124.46) (diameter 0) (color 0 0 0 0)
  )
  (junction (at 314.325 147.32) (diameter 0) (color 0 0 0 0)
  )
  (junction (at 112.395 137.795) (diameter 0) (color 0 0 0 0)
  )
  (junction (at 314.325 109.22) (diameter 0) (color 0 0 0 0)
  )
  (junction (at 103.505 130.175) (diameter 0) (color 0 0 0 0)
  )
  (junction (at 314.325 132.08) (diameter 0) (color 0 0 0 0)
  )
  (junction (at 80.01 130.175) (diameter 0) (color 0 0 0 0)
  )
  (junction (at 103.505 140.335) (diameter 0) (color 0 0 0 0)
  )
  (junction (at 150.495 142.875) (diameter 0) (color 0 0 0 0)
  )
  (junction (at 314.325 139.7) (diameter 0) (color 0 0 0 0)
  )
  (junction (at 171.45 130.175) (diameter 0) (color 0 0 0 0)
  )
  (junction (at 147.955 140.335) (diameter 0) (color 0 0 0 0)
  )
  (junction (at 147.955 130.175) (diameter 0) (color 0 0 0 0)
  )
  (junction (at 150.495 130.175) (diameter 0) (color 0 0 0 0)
  )

  (no_connect (at 315.976 154.94))
  (no_connect (at 315.976 152.4))

  (wire (pts (xy 112.395 145.415) (xy 112.395 137.795))
    (stroke (width 0) (type default) (color 0 0 0 0))
  )
  (wire (pts (xy 259.08 129.54) (xy 315.976 129.54))
    (stroke (width 0) (type default) (color 0 0 0 0))
  )
  (wire (pts (xy 259.08 111.76) (xy 259.08 110.49))
    (stroke (width 0) (type default) (color 0 0 0 0))
  )
  (wire (pts (xy 150.495 142.875) (xy 167.64 142.875))
    (stroke (width 0) (type default) (color 0 0 0 0))
  )
  (wire (pts (xy 226.06 127) (xy 243.84 127))
    (stroke (width 0) (type default) (color 0 0 0 0))
  )
  (wire (pts (xy 139.065 137.795) (xy 135.89 137.795))
    (stroke (width 0) (type default) (color 0 0 0 0))
  )
  (wire (pts (xy 226.06 137.16) (xy 243.84 137.16))
    (stroke (width 0) (type default) (color 0 0 0 0))
  )
  (wire (pts (xy 100.965 137.541) (xy 100.965 142.875))
    (stroke (width 0) (type default) (color 0 0 0 0))
  )
  (wire (pts (xy 314.325 101.6) (xy 314.325 109.22))
    (stroke (width 0) (type default) (color 0 0 0 0))
  )
  (wire (pts (xy 314.325 147.32) (xy 314.325 155.829))
    (stroke (width 0) (type default) (color 0 0 0 0))
  )
  (wire (pts (xy 226.06 149.86) (xy 315.976 149.86))
    (stroke (width 0) (type default) (color 0 0 0 0))
  )
  (wire (pts (xy 150.495 130.175) (xy 171.45 130.175))
    (stroke (width 0) (type default) (color 0 0 0 0))
  )
  (wire (pts (xy 243.84 133.35) (xy 243.84 134.62))
    (stroke (width 0) (type default) (color 0 0 0 0))
  )
  (wire (pts (xy 177.8 130.175) (xy 171.45 130.175))
    (stroke (width 0) (type default) (color 0 0 0 0))
  )
  (wire (pts (xy 259.08 123.19) (xy 259.08 121.92))
    (stroke (width 0) (type default) (color 0 0 0 0))
  )
  (wire (pts (xy 314.325 132.08) (xy 314.325 139.7))
    (stroke (width 0) (type default) (color 0 0 0 0))
  )
  (wire (pts (xy 314.325 132.08) (xy 315.976 132.08))
    (stroke (width 0) (type default) (color 0 0 0 0))
  )
  (wire (pts (xy 243.84 138.43) (xy 243.84 137.16))
    (stroke (width 0) (type default) (color 0 0 0 0))
  )
  (wire (pts (xy 243.84 107.95) (xy 243.84 106.68))
    (stroke (width 0) (type default) (color 0 0 0 0))
  )
  (wire (pts (xy 73.66 130.175) (xy 80.01 130.175))
    (stroke (width 0) (type default) (color 0 0 0 0))
  )
  (wire (pts (xy 213.995 142.24) (xy 315.976 142.24))
    (stroke (width 0) (type default) (color 0 0 0 0))
  )
  (wire (pts (xy 243.84 102.87) (xy 243.84 104.14))
    (stroke (width 0) (type default) (color 0 0 0 0))
  )
  (wire (pts (xy 259.08 119.38) (xy 315.976 119.38))
    (stroke (width 0) (type default) (color 0 0 0 0))
  )
  (wire (pts (xy 115.57 145.415) (xy 112.395 145.415))
    (stroke (width 0) (type default) (color 0 0 0 0))
  )
  (wire (pts (xy 150.495 132.842) (xy 150.495 130.175))
    (stroke (width 0) (type default) (color 0 0 0 0))
  )
  (wire (pts (xy 100.965 142.875) (xy 97.155 142.875))
    (stroke (width 0) (type default) (color 0 0 0 0))
  )
  (wire (pts (xy 259.08 121.92) (xy 315.976 121.92))
    (stroke (width 0) (type default) (color 0 0 0 0))
  )
  (wire (pts (xy 314.325 124.46) (xy 315.976 124.46))
    (stroke (width 0) (type default) (color 0 0 0 0))
  )
  (wire (pts (xy 259.08 134.62) (xy 259.08 133.35))
    (stroke (width 0) (type default) (color 0 0 0 0))
  )
  (wire (pts (xy 243.84 115.57) (xy 243.84 114.3))
    (stroke (width 0) (type default) (color 0 0 0 0))
  )
  (wire (pts (xy 80.01 130.175) (xy 100.965 130.175))
    (stroke (width 0) (type default) (color 0 0 0 0))
  )
  (wire (pts (xy 259.08 138.43) (xy 259.08 137.16))
    (stroke (width 0) (type default) (color 0 0 0 0))
  )
  (wire (pts (xy 147.955 130.175) (xy 150.495 130.175))
    (stroke (width 0) (type default) (color 0 0 0 0))
  )
  (wire (pts (xy 259.08 114.3) (xy 315.976 114.3))
    (stroke (width 0) (type default) (color 0 0 0 0))
  )
  (wire (pts (xy 226.06 104.14) (xy 243.84 104.14))
    (stroke (width 0) (type default) (color 0 0 0 0))
  )
  (wire (pts (xy 226.06 114.3) (xy 243.84 114.3))
    (stroke (width 0) (type default) (color 0 0 0 0))
  )
  (wire (pts (xy 147.955 132.842) (xy 147.955 130.175))
    (stroke (width 0) (type default) (color 0 0 0 0))
  )
  (wire (pts (xy 314.325 116.84) (xy 314.325 124.46))
    (stroke (width 0) (type default) (color 0 0 0 0))
  )
  (wire (pts (xy 150.495 137.922) (xy 150.495 142.875))
    (stroke (width 0) (type default) (color 0 0 0 0))
  )
  (wire (pts (xy 226.06 111.76) (xy 243.84 111.76))
    (stroke (width 0) (type default) (color 0 0 0 0))
  )
  (wire (pts (xy 139.065 130.175) (xy 147.955 130.175))
    (stroke (width 0) (type default) (color 0 0 0 0))
  )
  (wire (pts (xy 103.505 137.541) (xy 103.505 140.335))
    (stroke (width 0) (type default) (color 0 0 0 0))
  )
  (wire (pts (xy 259.08 104.14) (xy 259.08 102.87))
    (stroke (width 0) (type default) (color 0 0 0 0))
  )
  (wire (pts (xy 226.06 119.38) (xy 243.84 119.38))
    (stroke (width 0) (type default) (color 0 0 0 0))
  )
  (wire (pts (xy 103.505 140.335) (xy 115.57 140.335))
    (stroke (width 0) (type default) (color 0 0 0 0))
  )
  (wire (pts (xy 100.965 130.175) (xy 103.505 130.175))
    (stroke (width 0) (type default) (color 0 0 0 0))
  )
  (wire (pts (xy 314.325 116.84) (xy 315.976 116.84))
    (stroke (width 0) (type default) (color 0 0 0 0))
  )
  (wire (pts (xy 243.84 110.49) (xy 243.84 111.76))
    (stroke (width 0) (type default) (color 0 0 0 0))
  )
  (wire (pts (xy 139.065 130.175) (xy 139.065 137.795))
    (stroke (width 0) (type default) (color 0 0 0 0))
  )
  (wire (pts (xy 259.08 127) (xy 259.08 125.73))
    (stroke (width 0) (type default) (color 0 0 0 0))
  )
  (wire (pts (xy 259.08 130.81) (xy 259.08 129.54))
    (stroke (width 0) (type default) (color 0 0 0 0))
  )
  (wire (pts (xy 112.395 137.795) (xy 115.57 137.795))
    (stroke (width 0) (type default) (color 0 0 0 0))
  )
  (wire (pts (xy 243.84 118.11) (xy 243.84 119.38))
    (stroke (width 0) (type default) (color 0 0 0 0))
  )
  (wire (pts (xy 314.325 124.46) (xy 314.325 132.08))
    (stroke (width 0) (type default) (color 0 0 0 0))
  )
  (wire (pts (xy 314.325 139.7) (xy 314.325 147.32))
    (stroke (width 0) (type default) (color 0 0 0 0))
  )
  (wire (pts (xy 135.89 140.335) (xy 147.955 140.335))
    (stroke (width 0) (type default) (color 0 0 0 0))
  )
  (wire (pts (xy 226.06 106.68) (xy 243.84 106.68))
    (stroke (width 0) (type default) (color 0 0 0 0))
  )
  (wire (pts (xy 100.965 132.461) (xy 100.965 130.175))
    (stroke (width 0) (type default) (color 0 0 0 0))
  )
  (wire (pts (xy 226.06 134.62) (xy 243.84 134.62))
    (stroke (width 0) (type default) (color 0 0 0 0))
  )
  (wire (pts (xy 135.89 142.875) (xy 150.495 142.875))
    (stroke (width 0) (type default) (color 0 0 0 0))
  )
  (wire (pts (xy 259.08 119.38) (xy 259.08 118.11))
    (stroke (width 0) (type default) (color 0 0 0 0))
  )
  (wire (pts (xy 259.08 107.95) (xy 259.08 106.68))
    (stroke (width 0) (type default) (color 0 0 0 0))
  )
  (wire (pts (xy 103.505 132.461) (xy 103.505 130.175))
    (stroke (width 0) (type default) (color 0 0 0 0))
  )
  (wire (pts (xy 314.325 147.32) (xy 315.976 147.32))
    (stroke (width 0) (type default) (color 0 0 0 0))
  )
  (wire (pts (xy 259.08 106.68) (xy 315.976 106.68))
    (stroke (width 0) (type default) (color 0 0 0 0))
  )
  (wire (pts (xy 243.84 130.81) (xy 243.84 129.54))
    (stroke (width 0) (type default) (color 0 0 0 0))
  )
  (wire (pts (xy 259.08 111.76) (xy 315.976 111.76))
    (stroke (width 0) (type default) (color 0 0 0 0))
  )
  (wire (pts (xy 115.57 142.875) (xy 100.965 142.875))
    (stroke (width 0) (type default) (color 0 0 0 0))
  )
  (wire (pts (xy 226.06 121.92) (xy 243.84 121.92))
    (stroke (width 0) (type default) (color 0 0 0 0))
  )
  (wire (pts (xy 135.89 145.415) (xy 137.16 145.415))
    (stroke (width 0) (type default) (color 0 0 0 0))
  )
  (wire (pts (xy 147.955 137.922) (xy 147.955 140.335))
    (stroke (width 0) (type default) (color 0 0 0 0))
  )
  (wire (pts (xy 259.08 104.14) (xy 315.976 104.14))
    (stroke (width 0) (type default) (color 0 0 0 0))
  )
  (wire (pts (xy 112.395 130.175) (xy 112.395 137.795))
    (stroke (width 0) (type default) (color 0 0 0 0))
  )
  (wire (pts (xy 259.08 115.57) (xy 259.08 114.3))
    (stroke (width 0) (type default) (color 0 0 0 0))
  )
  (wire (pts (xy 314.325 139.7) (xy 315.976 139.7))
    (stroke (width 0) (type default) (color 0 0 0 0))
  )
  (wire (pts (xy 259.08 127) (xy 315.976 127))
    (stroke (width 0) (type default) (color 0 0 0 0))
  )
  (wire (pts (xy 314.325 109.22) (xy 315.976 109.22))
    (stroke (width 0) (type default) (color 0 0 0 0))
  )
  (wire (pts (xy 80.01 130.175) (xy 80.01 131.445))
    (stroke (width 0) (type default) (color 0 0 0 0))
  )
  (wire (pts (xy 243.84 125.73) (xy 243.84 127))
    (stroke (width 0) (type default) (color 0 0 0 0))
  )
  (wire (pts (xy 259.08 137.16) (xy 315.976 137.16))
    (stroke (width 0) (type default) (color 0 0 0 0))
  )
  (wire (pts (xy 171.45 130.175) (xy 171.45 131.445))
    (stroke (width 0) (type default) (color 0 0 0 0))
  )
  (wire (pts (xy 259.08 134.62) (xy 315.976 134.62))
    (stroke (width 0) (type default) (color 0 0 0 0))
  )
  (wire (pts (xy 147.955 140.335) (xy 167.64 140.335))
    (stroke (width 0) (type default) (color 0 0 0 0))
  )
  (wire (pts (xy 314.325 109.22) (xy 314.325 116.84))
    (stroke (width 0) (type default) (color 0 0 0 0))
  )
  (wire (pts (xy 213.995 144.78) (xy 315.976 144.78))
    (stroke (width 0) (type default) (color 0 0 0 0))
  )
  (wire (pts (xy 97.155 140.335) (xy 103.505 140.335))
    (stroke (width 0) (type default) (color 0 0 0 0))
  )
  (wire (pts (xy 315.976 101.6) (xy 314.325 101.6))
    (stroke (width 0) (type default) (color 0 0 0 0))
  )
  (wire (pts (xy 226.06 129.54) (xy 243.84 129.54))
    (stroke (width 0) (type default) (color 0 0 0 0))
  )
  (wire (pts (xy 243.84 123.19) (xy 243.84 121.92))
    (stroke (width 0) (type default) (color 0 0 0 0))
  )
  (wire (pts (xy 137.16 145.415) (xy 137.16 146.685))
    (stroke (width 0) (type default) (color 0 0 0 0))
  )
  (wire (pts (xy 103.505 130.175) (xy 112.395 130.175))
    (stroke (width 0) (type default) (color 0 0 0 0))
  )

  (text "DSI LDC connector" (at 13.335 18.415 0)
    (effects (font (size 2.9972 2.9972) (thickness 0.5994) bold) (justify left bottom))
  )

  (label "DSI_LN0_L_P" (at 285.75 129.54 0)
    (effects (font (size 1.27 1.27)) (justify left bottom))
  )
  (label "TP_I2C_SCL_3V3" (at 167.64 140.335 180)
    (effects (font (size 1.27 1.27)) (justify right bottom))
  )
  (label "DSI_LN3_L_N" (at 285.75 104.14 0)
    (effects (font (size 1.27 1.27)) (justify left bottom))
  )
  (label "DSI_LN2_L_N" (at 285.75 111.76 0)
    (effects (font (size 1.27 1.27)) (justify left bottom))
  )
  (label "TP_I2C_SDA_3V3" (at 213.995 144.78 0)
    (effects (font (size 1.27 1.27)) (justify left bottom))
  )
  (label "DSI_LN1_L_P" (at 285.75 121.92 0)
    (effects (font (size 1.27 1.27)) (justify left bottom))
  )
  (label "DSI_LN3_L_P" (at 285.75 106.68 0)
    (effects (font (size 1.27 1.27)) (justify left bottom))
  )
  (label "DSI_LN0_L_N" (at 285.75 127 0)
    (effects (font (size 1.27 1.27)) (justify left bottom))
  )
  (label "TP_I2C_SCL_3V3" (at 213.995 142.24 0)
    (effects (font (size 1.27 1.27)) (justify left bottom))
  )
  (label "DSI_LN1_L_N" (at 285.75 119.38 0)
    (effects (font (size 1.27 1.27)) (justify left bottom))
  )
  (label "DSI_LN2_L_P" (at 285.75 114.3 0)
    (effects (font (size 1.27 1.27)) (justify left bottom))
  )
  (label "TP_I2C_SDA_3V3" (at 167.64 142.875 180)
    (effects (font (size 1.27 1.27)) (justify right bottom))
  )
  (label "DSI_CLK_L_P" (at 285.75 137.16 0)
    (effects (font (size 1.27 1.27)) (justify left bottom))
  )
  (label "DSI_CLK_L_N" (at 285.75 134.62 0)
    (effects (font (size 1.27 1.27)) (justify left bottom))
  )

  (global_label "DSI0_LN1_N" (shape input) (at 226.06 119.38 180) (fields_autoplaced)
    (effects (font (size 1.27 1.27)) (justify right))
    (property "Intersheet References" "${INTERSHEET_REFS}" (id 0) (at 0 0 0)
      (effects (font (size 1.27 1.27)) hide)
    )
  )
  (global_label "DSI0_LN2_P" (shape input) (at 226.06 114.3 180) (fields_autoplaced)
    (effects (font (size 1.27 1.27)) (justify right))
    (property "Intersheet References" "${INTERSHEET_REFS}" (id 0) (at 0 0 0)
      (effects (font (size 1.27 1.27)) hide)
    )
  )
  (global_label "DSI0_LN2_N" (shape input) (at 226.06 111.76 180) (fields_autoplaced)
    (effects (font (size 1.27 1.27)) (justify right))
    (property "Intersheet References" "${INTERSHEET_REFS}" (id 0) (at 0 0 0)
      (effects (font (size 1.27 1.27)) hide)
    )
  )
  (global_label "DSI0_LN3_P" (shape input) (at 226.06 106.68 180) (fields_autoplaced)
    (effects (font (size 1.27 1.27)) (justify right))
    (property "Intersheet References" "${INTERSHEET_REFS}" (id 0) (at 0 0 0)
      (effects (font (size 1.27 1.27)) hide)
    )
  )
  (global_label "DSI0_LN0_N" (shape input) (at 226.06 127 180) (fields_autoplaced)
    (effects (font (size 1.27 1.27)) (justify right))
    (property "Intersheet References" "${INTERSHEET_REFS}" (id 0) (at 0 0 0)
      (effects (font (size 1.27 1.27)) hide)
    )
  )
  (global_label "3V3_SYS" (shape input) (at 177.8 130.175 0) (fields_autoplaced)
    (effects (font (size 1.27 1.27)) (justify left))
    (property "Intersheet References" "${INTERSHEET_REFS}" (id 0) (at 0 0 0)
      (effects (font (size 1.27 1.27)) hide)
    )
  )
  (global_label "DSI0_CLK_N" (shape input) (at 226.06 134.62 180) (fields_autoplaced)
    (effects (font (size 1.27 1.27)) (justify right))
    (property "Intersheet References" "${INTERSHEET_REFS}" (id 0) (at 0 0 0)
      (effects (font (size 1.27 1.27)) hide)
    )
  )
  (global_label "DSI0_LN0_P" (shape input) (at 226.06 129.54 180) (fields_autoplaced)
    (effects (font (size 1.27 1.27)) (justify right))
    (property "Intersheet References" "${INTERSHEET_REFS}" (id 0) (at 0 0 0)
      (effects (font (size 1.27 1.27)) hide)
    )
  )
  (global_label "3V3_SYS" (shape input) (at 226.06 149.86 180) (fields_autoplaced)
    (effects (font (size 1.27 1.27)) (justify right))
    (property "Intersheet References" "${INTERSHEET_REFS}" (id 0) (at 0 0 0)
      (effects (font (size 1.27 1.27)) hide)
    )
  )
  (global_label "DSI0_LN3_N" (shape input) (at 226.06 104.14 180) (fields_autoplaced)
    (effects (font (size 1.27 1.27)) (justify right))
    (property "Intersheet References" "${INTERSHEET_REFS}" (id 0) (at 0 0 0)
      (effects (font (size 1.27 1.27)) hide)
    )
  )
  (global_label "LVS1A_1V8" (shape input) (at 73.66 130.175 180) (fields_autoplaced)
    (effects (font (size 1.27 1.27)) (justify right))
    (property "Intersheet References" "${INTERSHEET_REFS}" (id 0) (at 0 0 0)
      (effects (font (size 1.27 1.27)) hide)
    )
  )
  (global_label "TP_I2C_SDA" (shape bidirectional) (at 97.155 142.875 180) (fields_autoplaced)
    (effects (font (size 1.27 1.27)) (justify right))
    (property "Intersheet References" "${INTERSHEET_REFS}" (id 0) (at 0 0 0)
      (effects (font (size 1.27 1.27)) hide)
    )
  )
  (global_label "DSI0_LN1_P" (shape input) (at 226.06 121.92 180) (fields_autoplaced)
    (effects (font (size 1.27 1.27)) (justify right))
    (property "Intersheet References" "${INTERSHEET_REFS}" (id 0) (at 0 0 0)
      (effects (font (size 1.27 1.27)) hide)
    )
  )
  (global_label "DSI0_CLK_P" (shape input) (at 226.06 137.16 180) (fields_autoplaced)
    (effects (font (size 1.27 1.27)) (justify right))
    (property "Intersheet References" "${INTERSHEET_REFS}" (id 0) (at 0 0 0)
      (effects (font (size 1.27 1.27)) hide)
    )
  )
  (global_label "TP_I2C_SCL" (shape input) (at 97.155 140.335 180) (fields_autoplaced)
    (effects (font (size 1.27 1.27)) (justify right))
    (property "Intersheet References" "${INTERSHEET_REFS}" (id 0) (at 0 0 0)
      (effects (font (size 1.27 1.27)) hide)
    )
  )

  (symbol (lib_id "sa800u-baseboard-hw:F52R-1A7H1-11020") (at 315.976 99.06 0) (unit 1)
    (in_bom yes) (on_board yes) (fields_autoplaced)
    (property "Reference" "J6" (id 0) (at 327.66 124.4599 0)
      (effects (font (size 1.27 1.27)) (justify left))
    )
    (property "Value" "F52R-1A7H1-11020" (id 1) (at 327.66 126.9999 0)
      (effects (font (size 1.27 1.27)) (justify left))
    )
    (property "Footprint" "sa800u-baseboard-hw-footprints:F52R-1A7H1-11020" (id 2) (at 315.976 99.06 0)
      (effects (font (size 1.27 1.27)) hide)
    )
    (property "Datasheet" "https://www.snapeda.com/parts/F52R-1A7H1-11020/Amphenol%20ICC%20(FCI)/datasheet/" (id 3) (at 315.976 99.06 0)
      (effects (font (size 1.27 1.27)) hide)
    )
    (property "MPN" "F52R-1A7H1-11020" (id 4) (at 324.3072 126.873 0)
      (effects (font (size 1.27 1.27)) (justify left) hide)
    )
    (property "Manufacturer" "Amphenol" (id 5) (at 324.3072 129.1844 0)
      (effects (font (size 1.27 1.27)) (justify left) hide)
    )
    (property "Author" "Antmicro" (id 6) (at 341.376 119.38 0)
      (effects (font (size 1.27 1.27) (thickness 0.15)) (justify left bottom) hide)
    )
    (property "License" "Apache-2.0" (id 7) (at 341.376 121.92 0)
      (effects (font (size 1.27 1.27) (thickness 0.15)) (justify left bottom) hide)
    )
    (pin "1")
    (pin "10")
    (pin "11")
    (pin "12")
    (pin "13")
    (pin "14")
    (pin "15")
    (pin "16")
    (pin "17")
    (pin "18")
    (pin "19")
    (pin "2")
    (pin "20")
    (pin "21")
    (pin "22")
    (pin "3")
    (pin "4")
    (pin "5")
    (pin "6")
    (pin "7")
    (pin "8")
    (pin "9")
  )

  (symbol (lib_id "sa800u-baseboard-hw:GND") (at 314.325 155.829 0) (unit 1)
    (in_bom yes) (on_board yes) (fields_autoplaced)
    (property "Reference" "#PWR085" (id 0) (at 314.325 162.179 0)
      (effects (font (size 1.27 1.27)) hide)
    )
    (property "Value" "GND" (id 1) (at 314.325 160.909 0))
    (property "Footprint" "" (id 2) (at 314.325 155.829 0)
      (effects (font (size 1.27 1.27)) hide)
    )
    (property "Datasheet" "" (id 3) (at 314.325 155.829 0)
      (effects (font (size 1.27 1.27)) hide)
    )
    (property "Author" "Antmicro" (id 4) (at 323.215 163.449 0)
      (effects (font (size 1.27 1.27) (thickness 0.15)) (justify left bottom) hide)
    )
    (property "License" "Apache-2.0" (id 5) (at 323.215 165.989 0)
      (effects (font (size 1.27 1.27) (thickness 0.15)) (justify left bottom) hide)
    )
    (pin "1")
  )

  (symbol (lib_name "NFP0QHB242HS2D_2") (lib_id "sa800u-baseboard-hw:NFP0QHB242HS2D") (at 259.08 102.87 0) (mirror y) (unit 1)
    (in_bom yes) (on_board yes)
    (property "Reference" "L11" (id 0) (at 261.493 102.743 0))
    (property "Value" "NFP0QHB242HS2D" (id 1) (at 267.716 105.537 0))
    (property "Footprint" "sa800u-baseboard-hw-footprints:L_Murata_025020_0605Metric" (id 2) (at 259.08 102.87 0)
      (effects (font (size 1.27 1.27)) hide)
    )
    (property "Datasheet" "https://www.farnell.com/datasheets/2616945.pdf" (id 3) (at 259.08 102.87 0)
      (effects (font (size 1.27 1.27)) hide)
    )
    (property "MPN" "NFP0QHB242HS2D" (id 4) (at 259.08 92.2782 0)
      (effects (font (size 1.27 1.27)) hide)
    )
    (property "Manufacturer" "Murata" (id 5) (at 259.08 94.5896 0)
      (effects (font (size 1.27 1.27)) hide)
    )
    (property "Author" "Antmicro" (id 6) (at 227.33 123.19 0)
      (effects (font (size 1.27 1.27) (thickness 0.15)) (justify left bottom) hide)
    )
    (property "License" "Apache-2.0" (id 7) (at 227.33 125.73 0)
      (effects (font (size 1.27 1.27) (thickness 0.15)) (justify left bottom) hide)
    )
    (pin "1")
    (pin "2")
    (pin "3")
    (pin "4")
  )

  (symbol (lib_name "NFP0QHB242HS2D_3") (lib_id "sa800u-baseboard-hw:NFP0QHB242HS2D") (at 259.08 110.49 0) (mirror y) (unit 1)
    (in_bom yes) (on_board yes)
    (property "Reference" "L12" (id 0) (at 261.493 110.363 0))
    (property "Value" "NFP0QHB242HS2D" (id 1) (at 267.716 113.157 0))
    (property "Footprint" "sa800u-baseboard-hw-footprints:L_Murata_025020_0605Metric" (id 2) (at 259.08 110.49 0)
      (effects (font (size 1.27 1.27)) hide)
    )
    (property "Datasheet" "https://www.farnell.com/datasheets/2616945.pdf" (id 3) (at 259.08 110.49 0)
      (effects (font (size 1.27 1.27)) hide)
    )
    (property "MPN" "NFP0QHB242HS2D" (id 4) (at 259.08 99.8982 0)
      (effects (font (size 1.27 1.27)) hide)
    )
    (property "Manufacturer" "Murata" (id 5) (at 259.08 102.2096 0)
      (effects (font (size 1.27 1.27)) hide)
    )
    (property "Author" "Antmicro" (id 6) (at 227.33 130.81 0)
      (effects (font (size 1.27 1.27) (thickness 0.15)) (justify left bottom) hide)
    )
    (property "License" "Apache-2.0" (id 7) (at 227.33 133.35 0)
      (effects (font (size 1.27 1.27) (thickness 0.15)) (justify left bottom) hide)
    )
    (pin "1")
    (pin "2")
    (pin "3")
    (pin "4")
  )

  (symbol (lib_id "sa800u-baseboard-hw:NFP0QHB242HS2D") (at 259.08 118.11 0) (mirror y) (unit 1)
    (in_bom yes) (on_board yes)
    (property "Reference" "L13" (id 0) (at 261.493 117.983 0))
    (property "Value" "NFP0QHB242HS2D" (id 1) (at 267.716 120.777 0))
    (property "Footprint" "sa800u-baseboard-hw-footprints:L_Murata_025020_0605Metric" (id 2) (at 259.08 118.11 0)
      (effects (font (size 1.27 1.27)) hide)
    )
    (property "Datasheet" "https://www.farnell.com/datasheets/2616945.pdf" (id 3) (at 259.08 118.11 0)
      (effects (font (size 1.27 1.27)) hide)
    )
    (property "MPN" "NFP0QHB242HS2D" (id 4) (at 259.08 107.5182 0)
      (effects (font (size 1.27 1.27)) hide)
    )
    (property "Manufacturer" "Murata" (id 5) (at 259.08 109.8296 0)
      (effects (font (size 1.27 1.27)) hide)
    )
    (property "Author" "Antmicro" (id 6) (at 227.33 138.43 0)
      (effects (font (size 1.27 1.27) (thickness 0.15)) (justify left bottom) hide)
    )
    (property "License" "Apache-2.0" (id 7) (at 227.33 140.97 0)
      (effects (font (size 1.27 1.27) (thickness 0.15)) (justify left bottom) hide)
    )
    (pin "1")
    (pin "2")
    (pin "3")
    (pin "4")
  )

  (symbol (lib_name "NFP0QHB242HS2D_4") (lib_id "sa800u-baseboard-hw:NFP0QHB242HS2D") (at 259.08 125.73 0) (mirror y) (unit 1)
    (in_bom yes) (on_board yes)
    (property "Reference" "L14" (id 0) (at 261.493 125.603 0))
    (property "Value" "NFP0QHB242HS2D" (id 1) (at 267.716 128.397 0))
    (property "Footprint" "sa800u-baseboard-hw-footprints:L_Murata_025020_0605Metric" (id 2) (at 259.08 125.73 0)
      (effects (font (size 1.27 1.27)) hide)
    )
    (property "Datasheet" "https://www.farnell.com/datasheets/2616945.pdf" (id 3) (at 259.08 125.73 0)
      (effects (font (size 1.27 1.27)) hide)
    )
    (property "MPN" "NFP0QHB242HS2D" (id 4) (at 259.08 115.1382 0)
      (effects (font (size 1.27 1.27)) hide)
    )
    (property "Manufacturer" "Murata" (id 5) (at 259.08 117.4496 0)
      (effects (font (size 1.27 1.27)) hide)
    )
    (property "Author" "Antmicro" (id 6) (at 227.33 146.05 0)
      (effects (font (size 1.27 1.27) (thickness 0.15)) (justify left bottom) hide)
    )
    (property "License" "Apache-2.0" (id 7) (at 227.33 148.59 0)
      (effects (font (size 1.27 1.27) (thickness 0.15)) (justify left bottom) hide)
    )
    (pin "1")
    (pin "2")
    (pin "3")
    (pin "4")
  )

  (symbol (lib_name "NFP0QHB242HS2D_1") (lib_id "sa800u-baseboard-hw:NFP0QHB242HS2D") (at 259.08 133.35 0) (mirror y) (unit 1)
    (in_bom yes) (on_board yes)
    (property "Reference" "L15" (id 0) (at 261.366 133.477 0))
    (property "Value" "NFP0QHB242HS2D" (id 1) (at 267.716 136.017 0))
    (property "Footprint" "sa800u-baseboard-hw-footprints:L_Murata_025020_0605Metric" (id 2) (at 259.08 133.35 0)
      (effects (font (size 1.27 1.27)) hide)
    )
    (property "Datasheet" "https://www.farnell.com/datasheets/2616945.pdf" (id 3) (at 259.08 133.35 0)
      (effects (font (size 1.27 1.27)) hide)
    )
    (property "MPN" "NFP0QHB242HS2D" (id 4) (at 259.08 122.7582 0)
      (effects (font (size 1.27 1.27)) hide)
    )
    (property "Manufacturer" "Murata" (id 5) (at 259.08 125.0696 0)
      (effects (font (size 1.27 1.27)) hide)
    )
    (property "Author" "Antmicro" (id 6) (at 227.33 153.67 0)
      (effects (font (size 1.27 1.27) (thickness 0.15)) (justify left bottom) hide)
    )
    (property "License" "Apache-2.0" (id 7) (at 227.33 156.21 0)
      (effects (font (size 1.27 1.27) (thickness 0.15)) (justify left bottom) hide)
    )
    (pin "1")
    (pin "2")
    (pin "3")
    (pin "4")
  )

  (symbol (lib_id "sa800u-baseboard-hw:NTS0102_XSON") (at 115.57 137.795 0) (unit 1)
    (in_bom yes) (on_board yes) (fields_autoplaced)
    (property "Reference" "U10" (id 0) (at 125.73 129.54 0))
    (property "Value" "NTS0102_XSON" (id 1) (at 125.73 153.67 0)
      (effects (font (size 1.27 1.27)) hide)
    )
    (property "Footprint" "sa800u-baseboard-hw-footprints:XSON-8_1x1.95mm_P0.5mm" (id 2) (at 113.03 125.095 0)
      (effects (font (size 1.27 1.27)) hide)
    )
    (property "Datasheet" "http://www.farnell.com/datasheets/1760723.pdf" (id 3) (at 132.08 118.745 0)
      (effects (font (size 1.27 1.27)) hide)
    )
    (property "MPN" "NTS0102GT" (id 4) (at 125.73 132.08 0))
    (property "Manufacturer" "NXP" (id 5) (at 115.57 127.0254 0)
      (effects (font (size 1.27 1.27)) hide)
    )
    (property "Author" "Antmicro" (id 6) (at 151.13 155.575 0)
      (effects (font (size 1.27 1.27) (thickness 0.15)) (justify left bottom) hide)
    )
    (property "License" "Apache-2.0" (id 7) (at 151.13 158.115 0)
      (effects (font (size 1.27 1.27) (thickness 0.15)) (justify left bottom) hide)
    )
    (pin "1")
    (pin "2")
    (pin "3")
    (pin "4")
    (pin "5")
    (pin "6")
    (pin "7")
    (pin "8")
  )

  (symbol (lib_id "sa800u-baseboard-hw:C_100n_0402") (at 80.01 131.445 270) (unit 1)
    (in_bom yes) (on_board yes) (fields_autoplaced)
    (property "Reference" "C97" (id 0) (at 83.185 132.7213 90)
      (effects (font (size 1.524 1.524)) (justify left))
    )
    (property "Value" "C_100n_0402" (id 1) (at 76.2 131.445 0)
      (effects (font (size 1.524 1.524)) hide)
    )
    (property "Footprint" "sa800u-baseboard-hw-footprints:C_0402_1005Metric" (id 2) (at 85.09 136.525 0)
      (effects (font (size 1.524 1.524)) (justify left) hide)
    )
    (property "Datasheet" "https://search.murata.co.jp/Ceramy/image/img/A01X/G101/ENG/GRM155R61H104KE14-01.pdf" (id 3) (at 80.01 131.445 0)
      (effects (font (size 1.27 1.27)) hide)
    )
    (property "Manufacturer" "Murata" (id 4) (at 90.17 136.525 0)
      (effects (font (size 1.524 1.524)) (justify left) hide)
    )
    (property "MPN" "GRM155R61H104KE14D" (id 5) (at 87.63 136.525 0)
      (effects (font (size 1.524 1.524)) (justify left) hide)
    )
    (property "Val" "100n" (id 6) (at 83.185 135.8962 90)
      (effects (font (size 1.27 1.27)) (justify left))
    )
    (property "License" "Apache-2.0" (id 7) (at 57.15 151.765 0)
      (effects (font (size 1.27 1.27) (thickness 0.15)) (justify left bottom) hide)
    )
    (property "Author" "Antmicro" (id 8) (at 54.61 151.765 0)
      (effects (font (size 1.27 1.27) (thickness 0.15)) (justify left bottom) hide)
    )
    (property "Voltage" "50V" (id 9) (at 52.07 151.765 0)
      (effects (font (size 1.27 1.27)) (justify left bottom) hide)
    )
    (property "Dielectric" "X5R" (id 10) (at 49.53 151.765 0)
      (effects (font (size 1.27 1.27)) (justify left bottom) hide)
    )
    (pin "1")
    (pin "2")
  )

  (symbol (lib_id "sa800u-baseboard-hw:GND") (at 80.01 136.525 0) (unit 1)
    (in_bom yes) (on_board yes) (fields_autoplaced)
    (property "Reference" "#PWR082" (id 0) (at 80.01 142.875 0)
      (effects (font (size 1.27 1.27)) hide)
    )
    (property "Value" "GND" (id 1) (at 80.01 140.97 0))
    (property "Footprint" "" (id 2) (at 80.01 136.525 0)
      (effects (font (size 1.27 1.27)) hide)
    )
    (property "Datasheet" "" (id 3) (at 80.01 136.525 0)
      (effects (font (size 1.27 1.27)) hide)
    )
    (property "Author" "Antmicro" (id 4) (at 88.9 144.145 0)
      (effects (font (size 1.27 1.27) (thickness 0.15)) (justify left bottom) hide)
    )
    (property "License" "Apache-2.0" (id 5) (at 88.9 146.685 0)
      (effects (font (size 1.27 1.27) (thickness 0.15)) (justify left bottom) hide)
    )
    (pin "1")
  )

  (symbol (lib_id "sa800u-baseboard-hw:R_2k_0402") (at 100.965 137.541 90) (unit 1)
    (in_bom yes) (on_board yes) (fields_autoplaced)
    (property "Reference" "R65" (id 0) (at 99.06 133.731 90)
      (effects (font (size 1.524 1.524)) (justify left))
    )
    (property "Value" "R_2k_0402" (id 1) (at 104.775 137.541 0)
      (effects (font (size 1.524 1.524)) hide)
    )
    (property "Footprint" "sa800u-baseboard-hw-footprints:R_0402_1005Metric" (id 2) (at 95.885 132.461 0)
      (effects (font (size 1.524 1.524)) (justify left) hide)
    )
    (property "Datasheet" "https://www.bourns.com/docs/product-datasheets/cr.pdf" (id 3) (at 100.965 137.541 0)
      (effects (font (size 1.27 1.27)) hide)
    )
    (property "Manufacturer" "Bourns" (id 4) (at 90.805 132.461 0)
      (effects (font (size 1.524 1.524)) (justify left) hide)
    )
    (property "MPN" "CR0402-FX-2001GLF" (id 5) (at 93.345 132.461 0)
      (effects (font (size 1.524 1.524)) (justify left) hide)
    )
    (property "Val" "2k" (id 6) (at 99.06 136.9059 90)
      (effects (font (size 1.27 1.27)) (justify left))
    )
    (property "License" "Apache-2.0" (id 7) (at 126.365 117.221 0)
      (effects (font (size 1.27 1.27) (thickness 0.15)) (justify left bottom) hide)
    )
    (property "Author" "Antmicro" (id 8) (at 128.905 117.221 0)
      (effects (font (size 1.27 1.27) (thickness 0.15)) (justify left bottom) hide)
    )
    (property "Tolerance" "1%" (id 9) (at 111.125 117.221 0)
      (effects (font (size 1.27 1.27)) (justify left bottom) hide)
    )
    (pin "1")
    (pin "2")
  )

  (symbol (lib_id "sa800u-baseboard-hw:R_2k_0402") (at 103.505 137.541 90) (unit 1)
    (in_bom yes) (on_board yes) (fields_autoplaced)
    (property "Reference" "R66" (id 0) (at 105.41 133.731 90)
      (effects (font (size 1.524 1.524)) (justify right))
    )
    (property "Value" "R_2k_0402" (id 1) (at 107.315 137.541 0)
      (effects (font (size 1.524 1.524)) hide)
    )
    (property "Footprint" "sa800u-baseboard-hw-footprints:R_0402_1005Metric" (id 2) (at 98.425 132.461 0)
      (effects (font (size 1.524 1.524)) (justify left) hide)
    )
    (property "Datasheet" "https://www.bourns.com/docs/product-datasheets/cr.pdf" (id 3) (at 103.505 137.541 0)
      (effects (font (size 1.27 1.27)) hide)
    )
    (property "Manufacturer" "Bourns" (id 4) (at 93.345 132.461 0)
      (effects (font (size 1.524 1.524)) (justify left) hide)
    )
    (property "MPN" "CR0402-FX-2001GLF" (id 5) (at 95.885 132.461 0)
      (effects (font (size 1.524 1.524)) (justify left) hide)
    )
    (property "Val" "2k" (id 6) (at 105.41 136.9059 90)
      (effects (font (size 1.27 1.27)) (justify right))
    )
    (property "License" "Apache-2.0" (id 7) (at 128.905 117.221 0)
      (effects (font (size 1.27 1.27) (thickness 0.15)) (justify left bottom) hide)
    )
    (property "Author" "Antmicro" (id 8) (at 131.445 117.221 0)
      (effects (font (size 1.27 1.27) (thickness 0.15)) (justify left bottom) hide)
    )
    (property "Tolerance" "1%" (id 9) (at 113.665 117.221 0)
      (effects (font (size 1.27 1.27)) (justify left bottom) hide)
    )
    (pin "1")
    (pin "2")
  )

  (symbol (lib_id "sa800u-baseboard-hw:C_100n_0402") (at 171.45 131.445 90) (mirror x) (unit 1)
    (in_bom yes) (on_board yes) (fields_autoplaced)
    (property "Reference" "C98" (id 0) (at 173.99 132.7213 90)
      (effects (font (size 1.524 1.524)) (justify right))
    )
    (property "Value" "C_100n_0402" (id 1) (at 175.26 131.445 0)
      (effects (font (size 1.524 1.524)) hide)
    )
    (property "Footprint" "sa800u-baseboard-hw-footprints:C_0402_1005Metric" (id 2) (at 166.37 136.525 0)
      (effects (font (size 1.524 1.524)) (justify left) hide)
    )
    (property "Datasheet" "https://search.murata.co.jp/Ceramy/image/img/A01X/G101/ENG/GRM155R61H104KE14-01.pdf" (id 3) (at 171.45 131.445 0)
      (effects (font (size 1.27 1.27)) hide)
    )
    (property "Manufacturer" "Murata" (id 4) (at 161.29 136.525 0)
      (effects (font (size 1.524 1.524)) (justify left) hide)
    )
    (property "MPN" "GRM155R61H104KE14D" (id 5) (at 163.83 136.525 0)
      (effects (font (size 1.524 1.524)) (justify left) hide)
    )
    (property "Val" "100n" (id 6) (at 173.99 135.8962 90)
      (effects (font (size 1.27 1.27)) (justify right))
    )
    (property "License" "Apache-2.0" (id 7) (at 194.31 151.765 0)
      (effects (font (size 1.27 1.27) (thickness 0.15)) (justify left bottom) hide)
    )
    (property "Author" "Antmicro" (id 8) (at 196.85 151.765 0)
      (effects (font (size 1.27 1.27) (thickness 0.15)) (justify left bottom) hide)
    )
    (property "Voltage" "50V" (id 9) (at 199.39 151.765 0)
      (effects (font (size 1.27 1.27)) (justify left bottom) hide)
    )
    (property "Dielectric" "X5R" (id 10) (at 201.93 151.765 0)
      (effects (font (size 1.27 1.27)) (justify left bottom) hide)
    )
    (pin "1")
    (pin "2")
  )

  (symbol (lib_id "sa800u-baseboard-hw:GND") (at 171.45 136.525 0) (mirror y) (unit 1)
    (in_bom yes) (on_board yes) (fields_autoplaced)
    (property "Reference" "#PWR084" (id 0) (at 171.45 142.875 0)
      (effects (font (size 1.27 1.27)) hide)
    )
    (property "Value" "GND" (id 1) (at 171.45 140.97 0))
    (property "Footprint" "" (id 2) (at 171.45 136.525 0)
      (effects (font (size 1.27 1.27)) hide)
    )
    (property "Datasheet" "" (id 3) (at 171.45 136.525 0)
      (effects (font (size 1.27 1.27)) hide)
    )
    (property "Author" "Antmicro" (id 4) (at 162.56 144.145 0)
      (effects (font (size 1.27 1.27) (thickness 0.15)) (justify left bottom) hide)
    )
    (property "License" "Apache-2.0" (id 5) (at 162.56 146.685 0)
      (effects (font (size 1.27 1.27) (thickness 0.15)) (justify left bottom) hide)
    )
    (pin "1")
  )

  (symbol (lib_id "sa800u-baseboard-hw:R_2k_0402") (at 150.495 137.922 270) (mirror x) (unit 1)
    (in_bom yes) (on_board yes) (fields_autoplaced)
    (property "Reference" "R68" (id 0) (at 152.4 134.112 90)
      (effects (font (size 1.524 1.524)) (justify left))
    )
    (property "Value" "R_2k_0402" (id 1) (at 146.685 137.922 0)
      (effects (font (size 1.524 1.524)) hide)
    )
    (property "Footprint" "sa800u-baseboard-hw-footprints:R_0402_1005Metric" (id 2) (at 155.575 132.842 0)
      (effects (font (size 1.524 1.524)) (justify left) hide)
    )
    (property "Datasheet" "https://www.bourns.com/docs/product-datasheets/cr.pdf" (id 3) (at 150.495 137.922 0)
      (effects (font (size 1.27 1.27)) hide)
    )
    (property "Manufacturer" "Bourns" (id 4) (at 160.655 132.842 0)
      (effects (font (size 1.524 1.524)) (justify left) hide)
    )
    (property "MPN" "CR0402-FX-2001GLF" (id 5) (at 158.115 132.842 0)
      (effects (font (size 1.524 1.524)) (justify left) hide)
    )
    (property "Val" "2k" (id 6) (at 152.4 137.2869 90)
      (effects (font (size 1.27 1.27)) (justify left))
    )
    (property "License" "Apache-2.0" (id 7) (at 125.095 117.602 0)
      (effects (font (size 1.27 1.27) (thickness 0.15)) (justify left bottom) hide)
    )
    (property "Author" "Antmicro" (id 8) (at 122.555 117.602 0)
      (effects (font (size 1.27 1.27) (thickness 0.15)) (justify left bottom) hide)
    )
    (property "Tolerance" "1%" (id 9) (at 140.335 117.602 0)
      (effects (font (size 1.27 1.27)) (justify left bottom) hide)
    )
    (pin "1")
    (pin "2")
  )

  (symbol (lib_id "sa800u-baseboard-hw:R_2k_0402") (at 147.955 137.922 270) (mirror x) (unit 1)
    (in_bom yes) (on_board yes) (fields_autoplaced)
    (property "Reference" "R67" (id 0) (at 146.05 134.112 90)
      (effects (font (size 1.524 1.524)) (justify right))
    )
    (property "Value" "R_2k_0402" (id 1) (at 144.145 137.922 0)
      (effects (font (size 1.524 1.524)) hide)
    )
    (property "Footprint" "sa800u-baseboard-hw-footprints:R_0402_1005Metric" (id 2) (at 153.035 132.842 0)
      (effects (font (size 1.524 1.524)) (justify left) hide)
    )
    (property "Datasheet" "https://www.bourns.com/docs/product-datasheets/cr.pdf" (id 3) (at 147.955 137.922 0)
      (effects (font (size 1.27 1.27)) hide)
    )
    (property "Manufacturer" "Bourns" (id 4) (at 158.115 132.842 0)
      (effects (font (size 1.524 1.524)) (justify left) hide)
    )
    (property "MPN" "CR0402-FX-2001GLF" (id 5) (at 155.575 132.842 0)
      (effects (font (size 1.524 1.524)) (justify left) hide)
    )
    (property "Val" "2k" (id 6) (at 146.05 137.2869 90)
      (effects (font (size 1.27 1.27)) (justify right))
    )
    (property "License" "Apache-2.0" (id 7) (at 122.555 117.602 0)
      (effects (font (size 1.27 1.27) (thickness 0.15)) (justify left bottom) hide)
    )
    (property "Author" "Antmicro" (id 8) (at 120.015 117.602 0)
      (effects (font (size 1.27 1.27) (thickness 0.15)) (justify left bottom) hide)
    )
    (property "Tolerance" "1%" (id 9) (at 137.795 117.602 0)
      (effects (font (size 1.27 1.27)) (justify left bottom) hide)
    )
    (pin "1")
    (pin "2")
  )

  (symbol (lib_id "sa800u-baseboard-hw:GND") (at 137.16 146.685 0) (mirror y) (unit 1)
    (in_bom yes) (on_board yes) (fields_autoplaced)
    (property "Reference" "#PWR083" (id 0) (at 137.16 153.035 0)
      (effects (font (size 1.27 1.27)) hide)
    )
    (property "Value" "GND" (id 1) (at 137.16 151.13 0))
    (property "Footprint" "" (id 2) (at 137.16 146.685 0)
      (effects (font (size 1.27 1.27)) hide)
    )
    (property "Datasheet" "" (id 3) (at 137.16 146.685 0)
      (effects (font (size 1.27 1.27)) hide)
    )
    (property "Author" "Antmicro" (id 4) (at 128.27 154.305 0)
      (effects (font (size 1.27 1.27) (thickness 0.15)) (justify left bottom) hide)
    )
    (property "License" "Apache-2.0" (id 5) (at 128.27 156.845 0)
      (effects (font (size 1.27 1.27) (thickness 0.15)) (justify left bottom) hide)
    )
    (pin "1")
  )
)
